FILE_TYPE = MACRO_DRAWING;
SET COLOR_WIRE YELLOW;
SET COLOR_PROP ORANGE;
SET COLOR_DOT WHITE;
SET COLOR_ARC YELLOW;
SET COLOR_BODY GREEN;
SET COLOR_NOTE PURPLE;
SET PROP_DISPLAY VALUE;
SET PAGE_NUMBER P2;
FORCEADD TABLE_TOC_CL..1
(1050 1850);
FORCEPROP 2 LAST CUSTOM_TXT_CDS <XR_PAGE_TITLE>
J 0
(-6320 7550);
DISPLAY 0.638298 (-6320 7550);
PAINT PINK (-6320 7550);
FORCEPROP 1 LAST CUSTOM_TXT_CDS <TITLE>
J 1
(-835 2455);
DISPLAY 0.978723 (-835 2455);
FORCEPROP 1 LAST CUSTOM_TXT_CDS <DOCREV>
J 0
(325 2225);
DISPLAY 0.978723 (325 2225);
FORCEPROP 1 LAST CUSTOM_TXT_CDS <DATE>
J 0
(325 2025);
DISPLAY 0.978723 (325 2025);
FORCEPROP 1 LAST CUSTOM_TXT_CDS <CON_PAGE_NUM>
J 0
(-1130 1900);
DISPLAY 0.978723 (-1130 1900);
FORCEPROP 1 LAST CUSTOM_TXT_CDS <CON_TOTAL_PAGES>
J 0
(-800 1900);
DISPLAY 0.978723 (-800 1900);
FORCEPROP 1 LAST CUSTOM_TXT_CDS <DESIGNER>
J 0
(325 2425);
DISPLAY 0.978723 (325 2425);
FORCEPROP 1 LAST CUSTOM_TXT_CDS <DOCNO>
J 0
(-900 2235);
DISPLAY 0.978723 (-900 2235);
FORCEPROP 1 LAST CUSTOM_TXT_CDS <ASSY_PN>
J 0
(-900 2025);
DISPLAY 0.978723 (-900 2025);
FORCEPROP 1 LAST PAGEREV_1 PAGE/REV
J 0
(-5800 6475);
DISPLAY 1.510638 (-5800 6475);
PAINT GREEN (-5800 6475);
FORCEPROP 1 LAST PAGEREV_2 PAGE/REV
J 0
(-2500 6475);
DISPLAY 1.510638 (-2500 6475);
PAINT GREEN (-2500 6475);
FORCEPROP 1 LAST TITLE TABLE OF CONTENT
J 0
(-3750 6850);
DISPLAY 2.957447 (-3750 6850);
PAINT GREEN (-3750 6850);
FORCEPROP 1 LAST COMMENT_BODY TRUE
J 0
(1060 1905);
DISPLAY 0.808511 (1060 1905);
DISPLAY INVISIBLE (1060 1905);
FORCEPROP 2 LAST PAGE_BORDER TRUE
J 0
(-6320 7550);
DISPLAY 0.638298 (-6320 7550);
PAINT PINK (-6320 7550);
DISPLAY INVISIBLE (-6320 7550);
FORCEPROP 1 LAST CDS_LMAN_SYM_OUTLINE -7700,5800,200,-200
J 0
(1050 1850);
DISPLAY 0.468085 (1050 1850);
PAINT GREEN (1050 1850);
DISPLAY INVISIBLE (1050 1850);
FORCEPROP 2 LAST CDS_LIB cls
J 0
(1050 1850);
DISPLAY INVISIBLE (1050 1850);
FORCEPROP 2 LAST CDS_XR_PAGE_TITLE CR-2 : @TIMECARD_LIB.TIMECARD(SCH_1):PAGE2
J 0
(-6320 7550);
DISPLAY 0.638298 (-6320 7550);
PAINT PINK (-6320 7550);
DISPLAY INVISIBLE (-6320 7550);
FORCENOTE
FPGA<>SMA CONN MAPPING
(-5000 5200) 0;
DISPLAY LEFT (-5000 5200);
DISPLAY 1.021277 (-5000 5200);
FORCENOTE
PCIEX4_GF_CONN
(-5000 5050) 0;
DISPLAY LEFT (-5000 5050);
DISPLAY 1.021277 (-5000 5050);
FORCENOTE
FPGA_5/5
(-5000 4300) 0;
DISPLAY LEFT (-5000 4300);
DISPLAY 1.021277 (-5000 4300);
FORCENOTE
PAGE 14
(-5700 4300) 0;
DISPLAY LEFT (-5700 4300);
DISPLAY 1.021277 (-5700 4300);
FORCENOTE
PAGE 13
(-5700 4450) 0;
DISPLAY LEFT (-5700 4450);
DISPLAY 1.021277 (-5700 4450);
FORCENOTE
FPGA_3/5
(-5000 4600) 0;
DISPLAY LEFT (-5000 4600);
DISPLAY 1.021277 (-5000 4600);
FORCENOTE
PAGE 9
(-5700 5050) 0;
DISPLAY LEFT (-5700 5050);
DISPLAY 1.021277 (-5700 5050);
FORCENOTE
FPGA_1/5
(-5000 4900) 0;
DISPLAY LEFT (-5000 4900);
DISPLAY 1.021277 (-5000 4900);
FORCENOTE
FPGA_2/5
(-5000 4750) 0;
DISPLAY LEFT (-5000 4750);
DISPLAY 1.021277 (-5000 4750);
FORCENOTE
FPGA_4/5
(-5000 4450) 0;
DISPLAY LEFT (-5000 4450);
DISPLAY 1.021277 (-5000 4450);
FORCENOTE
CLOCK_GENERATOR
(-5000 4150) 0;
DISPLAY LEFT (-5000 4150);
DISPLAY 1.021277 (-5000 4150);
FORCENOTE
PCA9546_I2C_SW&EEPROM
(-5000 4000) 0;
DISPLAY LEFT (-5000 4000);
DISPLAY 1.021277 (-5000 4000);
FORCENOTE
TEMPERATURE_SENSOR
(-5000 3850) 0;
DISPLAY LEFT (-5000 3850);
DISPLAY 1.021277 (-5000 3850);
FORCENOTE
HUMIDITY_SENSOR
(-5000 3700) 0;
DISPLAY LEFT (-5000 3700);
DISPLAY 1.021277 (-5000 3700);
FORCENOTE
AIR_PRESSURE_SENSOR
(-5000 3550) 0;
DISPLAY LEFT (-5000 3550);
DISPLAY 1.021277 (-5000 3550);
FORCENOTE
VIBRATION_SENSOR
(-5000 3400) 0;
DISPLAY LEFT (-5000 3400);
DISPLAY 1.021277 (-5000 3400);
FORCENOTE
MAC_MODULE_CONN
(-5000 3250) 0;
DISPLAY LEFT (-5000 3250);
DISPLAY 1.021277 (-5000 3250);
FORCENOTE
GPS_MODULE_CONN
(-5000 3100) 0;
DISPLAY LEFT (-5000 3100);
DISPLAY 1.021277 (-5000 3100);
FORCENOTE
SMA_CONN
(-5000 2950) 0;
DISPLAY LEFT (-5000 2950);
DISPLAY 1.021277 (-5000 2950);
FORCENOTE
USB2UART
(-5000 2800) 0;
DISPLAY LEFT (-5000 2800);
DISPLAY 1.021277 (-5000 2800);
FORCENOTE
PWR_SEQ_DIAGRAM
(-5000 5350) 0;
DISPLAY LEFT (-5000 5350);
DISPLAY 1.021277 (-5000 5350);
FORCENOTE
PAGE 24
(-5700 2800) 0;
DISPLAY LEFT (-5700 2800);
DISPLAY 1.021277 (-5700 2800);
FORCENOTE
PAGE 16
(-5700 4000) 0;
DISPLAY LEFT (-5700 4000);
DISPLAY 1.021277 (-5700 4000);
FORCENOTE
PAGE 15
(-5700 4150) 0;
DISPLAY LEFT (-5700 4150);
DISPLAY 1.021277 (-5700 4150);
FORCENOTE
TABLE OF CONTENT
(-5000 6100) 0;
DISPLAY LEFT (-5000 6100);
DISPLAY 1.021277 (-5000 6100);
FORCENOTE
COVER PAGE
(-5000 6250) 0;
DISPLAY LEFT (-5000 6250);
DISPLAY 1.021277 (-5000 6250);
FORCENOTE
PWR_BLOCK_DIAGRAM
(-5000 5500) 0;
DISPLAY LEFT (-5000 5500);
DISPLAY 1.021277 (-5000 5500);
FORCENOTE
USB2UART/MPSSE_CONNECTION_DIAGRAM
(-5000 5650) 0;
DISPLAY LEFT (-5000 5650);
DISPLAY 1.021277 (-5000 5650);
FORCENOTE
I2C_BLOCK_DIAGRAM
(-5000 5800) 0;
DISPLAY LEFT (-5000 5800);
DISPLAY 1.021277 (-5000 5800);
FORCENOTE
SYS_BLOCK_DIAGRAM
(-5000 5950) 0;
DISPLAY LEFT (-5000 5950);
DISPLAY 1.021277 (-5000 5950);
FORCENOTE
XP12R0V
(-1650 5950) 0;
DISPLAY LEFT (-1650 5950);
DISPLAY 1.021277 (-1650 5950);
FORCENOTE
XP3R3V
(-1650 5800) 0;
DISPLAY LEFT (-1650 5800);
DISPLAY 1.021277 (-1650 5800);
FORCENOTE
TEST_POINT
(-1650 6250) 0;
DISPLAY LEFT (-1650 6250);
DISPLAY 1.021277 (-1650 6250);
FORCENOTE
LED_INDICATOR
(-1650 6100) 0;
DISPLAY LEFT (-1650 6100);
DISPLAY 1.021277 (-1650 6100);
FORCENOTE
XP1R0V_FPGA
(-1650 5650) 0;
DISPLAY LEFT (-1650 5650);
DISPLAY 1.021277 (-1650 5650);
FORCENOTE
PAGE 35
(-2350 4750) 0;
DISPLAY LEFT (-2350 4750);
DISPLAY 1.021277 (-2350 4750);
FORCENOTE
PAGE 34
(-2350 4900) 0;
DISPLAY LEFT (-2350 4900);
DISPLAY 1.021277 (-2350 4900);
FORCENOTE
PAGE 32
(-2350 5200) 0;
DISPLAY LEFT (-2350 5200);
DISPLAY 1.021277 (-2350 5200);
FORCENOTE
PAGE 33
(-2350 5050) 0;
DISPLAY LEFT (-2350 5050);
DISPLAY 1.021277 (-2350 5050);
FORCENOTE
PAGE 30
(-2350 5500) 0;
DISPLAY LEFT (-2350 5500);
DISPLAY 1.021277 (-2350 5500);
FORCENOTE
PAGE 27
(-2350 5950) 0;
DISPLAY LEFT (-2350 5950);
DISPLAY 1.021277 (-2350 5950);
FORCENOTE
CHANGE_LIST
(-1650 4750) 0;
DISPLAY LEFT (-1650 4750);
DISPLAY 1.021277 (-1650 4750);
FORCENOTE
XP2R5V_FPGA&XP3R3V_FPGA
(-1650 5350) 0;
DISPLAY LEFT (-1650 5350);
DISPLAY 1.021277 (-1650 5350);
FORCENOTE
XP3R3V_FTDI
(-1650 5050) 0;
DISPLAY LEFT (-1650 5050);
DISPLAY 1.021277 (-1650 5050);
FORCENOTE
XP1R2V_FPGA & XP1R8V_FPGA
(-1650 5500) 0;
DISPLAY LEFT (-1650 5500);
DISPLAY 1.021277 (-1650 5500);
FORCENOTE
XP5R0V
(-1650 5200) 0;
DISPLAY LEFT (-1650 5200);
DISPLAY 1.021277 (-1650 5200);
FORCENOTE
MECH_PART
(-1650 4900) 0;
DISPLAY LEFT (-1650 4900);
DISPLAY 1.021277 (-1650 4900);
FORCENOTE
PAGE 26
(-2350 6100) 0;
DISPLAY LEFT (-2350 6100);
DISPLAY 1.021277 (-2350 6100);
FORCENOTE
PAGE 29
(-2350 5650) 0;
DISPLAY LEFT (-2350 5650);
DISPLAY 1.021277 (-2350 5650);
FORCENOTE
PAGE 28
(-2350 5800) 0;
DISPLAY LEFT (-2350 5800);
DISPLAY 1.021277 (-2350 5800);
FORCENOTE
PAGE 31
(-2350 5350) 0;
DISPLAY LEFT (-2350 5350);
DISPLAY 1.021277 (-2350 5350);
FORCENOTE
PAGE 25
(-2350 6250) 0;
DISPLAY LEFT (-2350 6250);
DISPLAY 1.021277 (-2350 6250);
FORCENOTE
PAGE 21
(-5700 3250) 0;
DISPLAY LEFT (-5700 3250);
DISPLAY 1.021277 (-5700 3250);
FORCENOTE
PAGE 19
(-5700 3550) 0;
DISPLAY LEFT (-5700 3550);
DISPLAY 1.021277 (-5700 3550);
FORCENOTE
PAGE 22
(-5700 3100) 0;
DISPLAY LEFT (-5700 3100);
DISPLAY 1.021277 (-5700 3100);
FORCENOTE
PAGE 17
(-5700 3850) 0;
DISPLAY LEFT (-5700 3850);
DISPLAY 1.021277 (-5700 3850);
FORCENOTE
PAGE 2
(-5700 6100) 0;
DISPLAY LEFT (-5700 6100);
DISPLAY 1.021277 (-5700 6100);
FORCENOTE
PAGE 18
(-5700 3700) 0;
DISPLAY LEFT (-5700 3700);
DISPLAY 1.021277 (-5700 3700);
FORCENOTE
PAGE 12
(-5700 4600) 0;
DISPLAY LEFT (-5700 4600);
DISPLAY 1.021277 (-5700 4600);
FORCENOTE
PAGE 1
(-5700 6250) 0;
DISPLAY LEFT (-5700 6250);
DISPLAY 1.021277 (-5700 6250);
FORCENOTE
PAGE 3
(-5700 5950) 0;
DISPLAY LEFT (-5700 5950);
DISPLAY 1.021277 (-5700 5950);
FORCENOTE
PAGE 10
(-5700 4900) 0;
DISPLAY LEFT (-5700 4900);
DISPLAY 1.021277 (-5700 4900);
FORCENOTE
PAGE 4
(-5700 5800) 0;
DISPLAY LEFT (-5700 5800);
DISPLAY 1.021277 (-5700 5800);
FORCENOTE
PAGE 23
(-5700 2950) 0;
DISPLAY LEFT (-5700 2950);
DISPLAY 1.021277 (-5700 2950);
FORCENOTE
PAGE 20
(-5700 3400) 0;
DISPLAY LEFT (-5700 3400);
DISPLAY 1.021277 (-5700 3400);
FORCENOTE
PAGE 11
(-5700 4750) 0;
DISPLAY LEFT (-5700 4750);
DISPLAY 1.021277 (-5700 4750);
FORCENOTE
PAGE 8
(-5700 5200) 0;
DISPLAY LEFT (-5700 5200);
DISPLAY 1.021277 (-5700 5200);
FORCENOTE
PAGE 6
(-5700 5500) 0;
DISPLAY LEFT (-5700 5500);
DISPLAY 1.021277 (-5700 5500);
FORCENOTE
PAGE 5
(-5700 5650) 0;
DISPLAY LEFT (-5700 5650);
DISPLAY 1.021277 (-5700 5650);
FORCENOTE
PAGE 7
(-5700 5350) 0;
DISPLAY LEFT (-5700 5350);
DISPLAY 1.021277 (-5700 5350);
QUIT
